(kicad_pcb
	(version 20260206)
	(generator "pcbnew")
	(generator_version "10.0")
	(general
		(thickness 1.6)
		(legacy_teardrops no)
	)
	(paper "A4")
	(title_block
		(title "03242023_DA0F0TMBIJ0_F0T_Motherboard_J_brd_V01_OCP.brd")
		(comment 1 "Grand Teton / footprints 328-333 of 6105")
	)
	(layers
		(0 "F.Cu" signal "TOP")
		(4 "In1.Cu" signal "GND")
		(6 "In2.Cu" signal "IN1")
		(8 "In3.Cu" signal "GND1")
		(10 "In4.Cu" signal "IN2")
		(12 "In5.Cu" signal "GND2")
		(14 "In6.Cu" signal "IN3")
		(16 "In7.Cu" signal "GND3")
		(18 "In8.Cu" signal "VCC")
		(20 "In9.Cu" signal "VCC1")
		(22 "In10.Cu" signal "GND4")
		(24 "In11.Cu" signal "IN4")
		(26 "In12.Cu" signal "GND5")
		(28 "In13.Cu" signal "IN5")
		(30 "In14.Cu" signal "GND6")
		(32 "In15.Cu" signal "IN6")
		(34 "In16.Cu" signal "GND7")
		(2 "B.Cu" signal "BOTTOM")
		(9 "F.Adhes" user "F.Adhesive")
		(11 "B.Adhes" user "B.Adhesive")
		(13 "F.Paste" user "Package Geometry/Pastemask Top")
		(15 "B.Paste" user "Package Geometry/Pastemask Bottom")
		(5 "F.SilkS" user "Ref Des/Silkscreen Top")
		(7 "B.SilkS" user "Ref Des/Silkscreen Bottom")
		(1 "F.Mask" user "Board Geometry/Soldermask Top")
		(3 "B.Mask" user "Board Geometry/Soldermask Bottom")
		(17 "Dwgs.User" user "User.Drawings")
		(19 "Cmts.User" user "User.Comments")
		(21 "Eco1.User" user "User.Eco1")
		(23 "Eco2.User" user "User.Eco2")
		(25 "Edge.Cuts" user "Board Geometry/Outline")
		(27 "Margin" user)
		(31 "F.CrtYd" user "Package Geometry/Place Bound Top")
		(29 "B.CrtYd" user "Package Geometry/Place Bound Bottom")
		(35 "F.Fab" user "Ref Des/Assembly Top")
		(33 "B.Fab" user "Ref Des/Assembly Bottom")
	)
	(footprint ""
		(layer "F.Cu")
		(at 40.627554 -110.587282 180)
		(property "Reference" "R3862"
			(at 0 0 180)
			(layer "F.SilkS")
			(hide yes)
			(effects
				(font
					(size 1.27 1.27)
				)
			)
		)
		(property "Value" ""
			(at 0 0 180)
			(layer "F.Fab")
			(effects
				(font
					(size 1.27 1.27)
				)
			)
		)
		(duplicate_pad_numbers_are_jumpers no)
		(fp_line
			(start 0.7874 0.4064)
			(end -0.7874 0.4064)
			(stroke
				(width 0.1524)
				(type default)
			)
			(layer "F.SilkS")
		)
		(fp_line
			(start 0.7874 -0.4064)
			(end 0.7874 0.4064)
			(stroke
				(width 0.1524)
				(type default)
			)
			(layer "F.SilkS")
		)
		(fp_line
			(start -0.7874 0.4064)
			(end -0.7874 -0.4064)
			(stroke
				(width 0.1524)
				(type default)
			)
			(layer "F.SilkS")
		)
		(fp_line
			(start -0.7874 -0.4064)
			(end 0.7874 -0.4064)
			(stroke
				(width 0.1524)
				(type default)
			)
			(layer "F.SilkS")
		)
		(fp_line
			(start 0.67945 0.3048)
			(end 0.120396 0.3048)
			(stroke
				(width 0.1)
				(type default)
			)
			(layer "F.Fab")
		)
		(fp_line
			(start 0.67945 -0.3048)
			(end 0.67945 0.3048)
			(stroke
				(width 0.1)
				(type default)
			)
			(layer "F.Fab")
		)
		(fp_line
			(start 0.12065 -0.2794)
			(end 0.12065 -0.3048)
			(stroke
				(width 0.1)
				(type default)
			)
			(layer "F.Fab")
		)
		(fp_line
			(start 0.12065 -0.3048)
			(end 0.67945 -0.3048)
			(stroke
				(width 0.1)
				(type default)
			)
			(layer "F.Fab")
		)
		(fp_line
			(start 0.120396 0.3048)
			(end 0.120396 0.2794)
			(stroke
				(width 0.1)
				(type default)
			)
			(layer "F.Fab")
		)
		(fp_line
			(start 0.120396 0.2794)
			(end -0.12065 0.2794)
			(stroke
				(width 0.1)
				(type default)
			)
			(layer "F.Fab")
		)
		(fp_line
			(start -0.12065 0.3048)
			(end -0.67945 0.3048)
			(stroke
				(width 0.1)
				(type default)
			)
			(layer "F.Fab")
		)
		(fp_line
			(start -0.12065 0.2794)
			(end -0.12065 0.3048)
			(stroke
				(width 0.1)
				(type default)
			)
			(layer "F.Fab")
		)
		(fp_line
			(start -0.12065 -0.2794)
			(end 0.12065 -0.2794)
			(stroke
				(width 0.1)
				(type default)
			)
			(layer "F.Fab")
		)
		(fp_line
			(start -0.12065 -0.305054)
			(end -0.12065 -0.2794)
			(stroke
				(width 0.1)
				(type default)
			)
			(layer "F.Fab")
		)
		(fp_line
			(start -0.67945 0.3048)
			(end -0.67945 -0.305054)
			(stroke
				(width 0.1)
				(type default)
			)
			(layer "F.Fab")
		)
		(fp_line
			(start -0.67945 -0.305054)
			(end -0.12065 -0.305054)
			(stroke
				(width 0.1)
				(type default)
			)
			(layer "F.Fab")
		)
		(pad "1" smd rect
			(at -0.40005 0)
			(size 0.4572 0.508)
			(layers "F.Cu" "F.Mask" "F.Paste")
			(net "P12V_OCP_V3_2_ISENSE_MPS_TIC")
		)
		(pad "2" smd rect
			(at 0.40005 0)
			(size 0.4572 0.508)
			(layers "F.Cu" "F.Mask" "F.Paste")
			(net "P12V_OCP_V3_2_ISENSE_TIC")
		)
	)
	(footprint ""
		(layer "F.Cu")
		(at 200.6346 -122.748548)
		(property "Reference" "R4608"
			(at 0 0 0)
			(layer "F.SilkS")
			(hide yes)
			(effects
				(font
					(size 1.27 1.27)
				)
			)
		)
		(property "Value" ""
			(at 0 0 0)
			(layer "F.Fab")
			(effects
				(font
					(size 1.27 1.27)
				)
			)
		)
		(duplicate_pad_numbers_are_jumpers no)
		(fp_line
			(start -0.7874 -0.4064)
			(end 0.7874 -0.4064)
			(stroke
				(width 0.1524)
				(type default)
			)
			(layer "F.SilkS")
		)
		(fp_line
			(start -0.7874 0.4064)
			(end -0.7874 -0.4064)
			(stroke
				(width 0.1524)
				(type default)
			)
			(layer "F.SilkS")
		)
		(fp_line
			(start 0.7874 -0.4064)
			(end 0.7874 0.4064)
			(stroke
				(width 0.1524)
				(type default)
			)
			(layer "F.SilkS")
		)
		(fp_line
			(start 0.7874 0.4064)
			(end -0.7874 0.4064)
			(stroke
				(width 0.1524)
				(type default)
			)
			(layer "F.SilkS")
		)
		(fp_line
			(start -0.67945 -0.305054)
			(end -0.12065 -0.305054)
			(stroke
				(width 0.1)
				(type default)
			)
			(layer "F.Fab")
		)
		(fp_line
			(start -0.67945 0.3048)
			(end -0.67945 -0.305054)
			(stroke
				(width 0.1)
				(type default)
			)
			(layer "F.Fab")
		)
		(fp_line
			(start -0.12065 -0.305054)
			(end -0.12065 -0.2794)
			(stroke
				(width 0.1)
				(type default)
			)
			(layer "F.Fab")
		)
		(fp_line
			(start -0.12065 -0.2794)
			(end 0.12065 -0.2794)
			(stroke
				(width 0.1)
				(type default)
			)
			(layer "F.Fab")
		)
		(fp_line
			(start -0.12065 0.2794)
			(end -0.12065 0.3048)
			(stroke
				(width 0.1)
				(type default)
			)
			(layer "F.Fab")
		)
		(fp_line
			(start -0.12065 0.3048)
			(end -0.67945 0.3048)
			(stroke
				(width 0.1)
				(type default)
			)
			(layer "F.Fab")
		)
		(fp_line
			(start 0.120396 0.2794)
			(end -0.12065 0.2794)
			(stroke
				(width 0.1)
				(type default)
			)
			(layer "F.Fab")
		)
		(fp_line
			(start 0.120396 0.3048)
			(end 0.120396 0.2794)
			(stroke
				(width 0.1)
				(type default)
			)
			(layer "F.Fab")
		)
		(fp_line
			(start 0.12065 -0.3048)
			(end 0.67945 -0.3048)
			(stroke
				(width 0.1)
				(type default)
			)
			(layer "F.Fab")
		)
		(fp_line
			(start 0.12065 -0.2794)
			(end 0.12065 -0.3048)
			(stroke
				(width 0.1)
				(type default)
			)
			(layer "F.Fab")
		)
		(fp_line
			(start 0.67945 -0.3048)
			(end 0.67945 0.3048)
			(stroke
				(width 0.1)
				(type default)
			)
			(layer "F.Fab")
		)
		(fp_line
			(start 0.67945 0.3048)
			(end 0.120396 0.3048)
			(stroke
				(width 0.1)
				(type default)
			)
			(layer "F.Fab")
		)
		(pad "1" smd circle
			(at -0.40005 0)
			(size 0 0)
			(layers "F.Cu" "F.Mask" "F.Paste")
			(net "GPU_FPGA_RST_N")
		)
		(pad "2" smd circle
			(at 0.40005 0)
			(size 0 0)
			(layers "F.Cu" "F.Mask" "F.Paste")
			(net "GPU_FPGA_RST_R_N")
		)
	)
	(footprint ""
		(layer "F.Cu")
		(at 63.194438 -29.398722 180)
		(property "Reference" "PR3851"
			(at 0 0 180)
			(layer "F.SilkS")
			(hide yes)
			(effects
				(font
					(size 1.27 1.27)
				)
			)
		)
		(property "Value" ""
			(at 0 0 180)
			(layer "F.Fab")
			(effects
				(font
					(size 1.27 1.27)
				)
			)
		)
		(duplicate_pad_numbers_are_jumpers no)
		(fp_line
			(start 0.7874 0.4064)
			(end -0.7874 0.4064)
			(stroke
				(width 0.1524)
				(type default)
			)
			(layer "F.SilkS")
		)
		(fp_line
			(start 0.7874 -0.4064)
			(end 0.7874 0.4064)
			(stroke
				(width 0.1524)
				(type default)
			)
			(layer "F.SilkS")
		)
		(fp_line
			(start -0.7874 0.4064)
			(end -0.7874 -0.4064)
			(stroke
				(width 0.1524)
				(type default)
			)
			(layer "F.SilkS")
		)
		(fp_line
			(start -0.7874 -0.4064)
			(end 0.7874 -0.4064)
			(stroke
				(width 0.1524)
				(type default)
			)
			(layer "F.SilkS")
		)
		(fp_line
			(start 0.67945 0.3048)
			(end 0.120396 0.3048)
			(stroke
				(width 0.1)
				(type default)
			)
			(layer "F.Fab")
		)
		(fp_line
			(start 0.67945 -0.3048)
			(end 0.67945 0.3048)
			(stroke
				(width 0.1)
				(type default)
			)
			(layer "F.Fab")
		)
		(fp_line
			(start 0.12065 -0.2794)
			(end 0.12065 -0.3048)
			(stroke
				(width 0.1)
				(type default)
			)
			(layer "F.Fab")
		)
		(fp_line
			(start 0.12065 -0.3048)
			(end 0.67945 -0.3048)
			(stroke
				(width 0.1)
				(type default)
			)
			(layer "F.Fab")
		)
		(fp_line
			(start 0.120396 0.3048)
			(end 0.120396 0.2794)
			(stroke
				(width 0.1)
				(type default)
			)
			(layer "F.Fab")
		)
		(fp_line
			(start 0.120396 0.2794)
			(end -0.12065 0.2794)
			(stroke
				(width 0.1)
				(type default)
			)
			(layer "F.Fab")
		)
		(fp_line
			(start -0.12065 0.3048)
			(end -0.67945 0.3048)
			(stroke
				(width 0.1)
				(type default)
			)
			(layer "F.Fab")
		)
		(fp_line
			(start -0.12065 0.2794)
			(end -0.12065 0.3048)
			(stroke
				(width 0.1)
				(type default)
			)
			(layer "F.Fab")
		)
		(fp_line
			(start -0.12065 -0.2794)
			(end 0.12065 -0.2794)
			(stroke
				(width 0.1)
				(type default)
			)
			(layer "F.Fab")
		)
		(fp_line
			(start -0.12065 -0.305054)
			(end -0.12065 -0.2794)
			(stroke
				(width 0.1)
				(type default)
			)
			(layer "F.Fab")
		)
		(fp_line
			(start -0.67945 0.3048)
			(end -0.67945 -0.305054)
			(stroke
				(width 0.1)
				(type default)
			)
			(layer "F.Fab")
		)
		(fp_line
			(start -0.67945 -0.305054)
			(end -0.12065 -0.305054)
			(stroke
				(width 0.1)
				(type default)
			)
			(layer "F.Fab")
		)
		(pad "1" smd circle
			(at -0.40005 0 180)
			(size 0 0)
			(layers "F.Cu" "F.Mask" "F.Paste")
			(net "P12V_OCP_FLTB_2")
		)
		(pad "2" smd circle
			(at 0.40005 0 180)
			(size 0 0)
			(layers "F.Cu" "F.Mask" "F.Paste")
			(net "P3V3_AUX")
		)
	)
	(footprint ""
		(layer "F.Cu")
		(at 357.735632 -397.519398)
		(property "Reference" "R2668"
			(at 0 0 0)
			(layer "F.SilkS")
			(hide yes)
			(effects
				(font
					(size 1.27 1.27)
				)
			)
		)
		(property "Value" ""
			(at 0 0 0)
			(layer "F.Fab")
			(effects
				(font
					(size 1.27 1.27)
				)
			)
		)
		(duplicate_pad_numbers_are_jumpers no)
		(fp_line
			(start -0.7874 -0.4064)
			(end 0.7874 -0.4064)
			(stroke
				(width 0.1524)
				(type default)
			)
			(layer "F.SilkS")
		)
		(fp_line
			(start -0.7874 0.4064)
			(end -0.7874 -0.4064)
			(stroke
				(width 0.1524)
				(type default)
			)
			(layer "F.SilkS")
		)
		(fp_line
			(start 0.7874 -0.4064)
			(end 0.7874 0.4064)
			(stroke
				(width 0.1524)
				(type default)
			)
			(layer "F.SilkS")
		)
		(fp_line
			(start 0.7874 0.4064)
			(end -0.7874 0.4064)
			(stroke
				(width 0.1524)
				(type default)
			)
			(layer "F.SilkS")
		)
		(fp_line
			(start -0.67945 -0.305054)
			(end -0.12065 -0.305054)
			(stroke
				(width 0.1)
				(type default)
			)
			(layer "F.Fab")
		)
		(fp_line
			(start -0.67945 0.3048)
			(end -0.67945 -0.305054)
			(stroke
				(width 0.1)
				(type default)
			)
			(layer "F.Fab")
		)
		(fp_line
			(start -0.12065 -0.305054)
			(end -0.12065 -0.2794)
			(stroke
				(width 0.1)
				(type default)
			)
			(layer "F.Fab")
		)
		(fp_line
			(start -0.12065 -0.2794)
			(end 0.12065 -0.2794)
			(stroke
				(width 0.1)
				(type default)
			)
			(layer "F.Fab")
		)
		(fp_line
			(start -0.12065 0.2794)
			(end -0.12065 0.3048)
			(stroke
				(width 0.1)
				(type default)
			)
			(layer "F.Fab")
		)
		(fp_line
			(start -0.12065 0.3048)
			(end -0.67945 0.3048)
			(stroke
				(width 0.1)
				(type default)
			)
			(layer "F.Fab")
		)
		(fp_line
			(start 0.120396 0.2794)
			(end -0.12065 0.2794)
			(stroke
				(width 0.1)
				(type default)
			)
			(layer "F.Fab")
		)
		(fp_line
			(start 0.120396 0.3048)
			(end 0.120396 0.2794)
			(stroke
				(width 0.1)
				(type default)
			)
			(layer "F.Fab")
		)
		(fp_line
			(start 0.12065 -0.3048)
			(end 0.67945 -0.3048)
			(stroke
				(width 0.1)
				(type default)
			)
			(layer "F.Fab")
		)
		(fp_line
			(start 0.12065 -0.2794)
			(end 0.12065 -0.3048)
			(stroke
				(width 0.1)
				(type default)
			)
			(layer "F.Fab")
		)
		(fp_line
			(start 0.67945 -0.3048)
			(end 0.67945 0.3048)
			(stroke
				(width 0.1)
				(type default)
			)
			(layer "F.Fab")
		)
		(fp_line
			(start 0.67945 0.3048)
			(end 0.120396 0.3048)
			(stroke
				(width 0.1)
				(type default)
			)
			(layer "F.Fab")
		)
		(pad "1" smd circle
			(at -0.40005 0)
			(size 0 0)
			(layers "F.Cu" "F.Mask" "F.Paste")
			(net "P3V3_AUX")
		)
		(pad "2" smd circle
			(at 0.40005 0)
			(size 0 0)
			(layers "F.Cu" "F.Mask" "F.Paste")
			(net "I3C_BMC_SWB_BUF_R_SDA")
		)
	)
	(footprint ""
		(layer "F.Cu")
		(at 369.228878 -394.647166 180)
		(property "Reference" "R4165"
			(at 0 0 180)
			(layer "F.SilkS")
			(hide yes)
			(effects
				(font
					(size 1.27 1.27)
				)
			)
		)
		(property "Value" ""
			(at 0 0 180)
			(layer "F.Fab")
			(effects
				(font
					(size 1.27 1.27)
				)
			)
		)
		(duplicate_pad_numbers_are_jumpers no)
		(fp_line
			(start 0.7874 0.4064)
			(end -0.7874 0.4064)
			(stroke
				(width 0.1524)
				(type default)
			)
			(layer "F.SilkS")
		)
		(fp_line
			(start 0.7874 -0.4064)
			(end 0.7874 0.4064)
			(stroke
				(width 0.1524)
				(type default)
			)
			(layer "F.SilkS")
		)
		(fp_line
			(start -0.7874 0.4064)
			(end -0.7874 -0.4064)
			(stroke
				(width 0.1524)
				(type default)
			)
			(layer "F.SilkS")
		)
		(fp_line
			(start -0.7874 -0.4064)
			(end 0.7874 -0.4064)
			(stroke
				(width 0.1524)
				(type default)
			)
			(layer "F.SilkS")
		)
		(fp_line
			(start 0.67945 0.3048)
			(end 0.120396 0.3048)
			(stroke
				(width 0.1)
				(type default)
			)
			(layer "F.Fab")
		)
		(fp_line
			(start 0.67945 -0.3048)
			(end 0.67945 0.3048)
			(stroke
				(width 0.1)
				(type default)
			)
			(layer "F.Fab")
		)
		(fp_line
			(start 0.12065 -0.2794)
			(end 0.12065 -0.3048)
			(stroke
				(width 0.1)
				(type default)
			)
			(layer "F.Fab")
		)
		(fp_line
			(start 0.12065 -0.3048)
			(end 0.67945 -0.3048)
			(stroke
				(width 0.1)
				(type default)
			)
			(layer "F.Fab")
		)
		(fp_line
			(start 0.120396 0.3048)
			(end 0.120396 0.2794)
			(stroke
				(width 0.1)
				(type default)
			)
			(layer "F.Fab")
		)
		(fp_line
			(start 0.120396 0.2794)
			(end -0.12065 0.2794)
			(stroke
				(width 0.1)
				(type default)
			)
			(layer "F.Fab")
		)
		(fp_line
			(start -0.12065 0.3048)
			(end -0.67945 0.3048)
			(stroke
				(width 0.1)
				(type default)
			)
			(layer "F.Fab")
		)
		(fp_line
			(start -0.12065 0.2794)
			(end -0.12065 0.3048)
			(stroke
				(width 0.1)
				(type default)
			)
			(layer "F.Fab")
		)
		(fp_line
			(start -0.12065 -0.2794)
			(end 0.12065 -0.2794)
			(stroke
				(width 0.1)
				(type default)
			)
			(layer "F.Fab")
		)
		(fp_line
			(start -0.12065 -0.305054)
			(end -0.12065 -0.2794)
			(stroke
				(width 0.1)
				(type default)
			)
			(layer "F.Fab")
		)
		(fp_line
			(start -0.67945 0.3048)
			(end -0.67945 -0.305054)
			(stroke
				(width 0.1)
				(type default)
			)
			(layer "F.Fab")
		)
		(fp_line
			(start -0.67945 -0.305054)
			(end -0.12065 -0.305054)
			(stroke
				(width 0.1)
				(type default)
			)
			(layer "F.Fab")
		)
		(pad "1" smd circle
			(at -0.40005 0 180)
			(size 0 0)
			(layers "F.Cu" "F.Mask" "F.Paste")
			(net "P3V3_AUX")
		)
		(pad "2" smd circle
			(at 0.40005 0 180)
			(size 0 0)
			(layers "F.Cu" "F.Mask" "F.Paste")
			(net "GPU_3V3IO_RSVD4_N")
		)
	)
	(footprint ""
		(layer "F.Cu")
		(at 385.734052 -68.126356 180)
		(property "Reference" "R776"
			(at 0 0 180)
			(layer "F.SilkS")
			(hide yes)
			(effects
				(font
					(size 1.27 1.27)
				)
			)
		)
		(property "Value" ""
			(at 0 0 180)
			(layer "F.Fab")
			(effects
				(font
					(size 1.27 1.27)
				)
			)
		)
		(duplicate_pad_numbers_are_jumpers no)
		(fp_line
			(start 0.7874 0.4064)
			(end -0.7874 0.4064)
			(stroke
				(width 0.1524)
				(type default)
			)
			(layer "F.SilkS")
		)
		(fp_line
			(start 0.7874 -0.4064)
			(end 0.7874 0.4064)
			(stroke
				(width 0.1524)
				(type default)
			)
			(layer "F.SilkS")
		)
		(fp_line
			(start -0.7874 0.4064)
			(end -0.7874 -0.4064)
			(stroke
				(width 0.1524)
				(type default)
			)
			(layer "F.SilkS")
		)
		(fp_line
			(start -0.7874 -0.4064)
			(end 0.7874 -0.4064)
			(stroke
				(width 0.1524)
				(type default)
			)
			(layer "F.SilkS")
		)
		(fp_line
			(start 0.67945 0.3048)
			(end 0.120396 0.3048)
			(stroke
				(width 0.1)
				(type default)
			)
			(layer "F.Fab")
		)
		(fp_line
			(start 0.67945 -0.3048)
			(end 0.67945 0.3048)
			(stroke
				(width 0.1)
				(type default)
			)
			(layer "F.Fab")
		)
		(fp_line
			(start 0.12065 -0.2794)
			(end 0.12065 -0.3048)
			(stroke
				(width 0.1)
				(type default)
			)
			(layer "F.Fab")
		)
		(fp_line
			(start 0.12065 -0.3048)
			(end 0.67945 -0.3048)
			(stroke
				(width 0.1)
				(type default)
			)
			(layer "F.Fab")
		)
		(fp_line
			(start 0.120396 0.3048)
			(end 0.120396 0.2794)
			(stroke
				(width 0.1)
				(type default)
			)
			(layer "F.Fab")
		)
		(fp_line
			(start 0.120396 0.2794)
			(end -0.12065 0.2794)
			(stroke
				(width 0.1)
				(type default)
			)
			(layer "F.Fab")
		)
		(fp_line
			(start -0.12065 0.3048)
			(end -0.67945 0.3048)
			(stroke
				(width 0.1)
				(type default)
			)
			(layer "F.Fab")
		)
		(fp_line
			(start -0.12065 0.2794)
			(end -0.12065 0.3048)
			(stroke
				(width 0.1)
				(type default)
			)
			(layer "F.Fab")
		)
		(fp_line
			(start -0.12065 -0.2794)
			(end 0.12065 -0.2794)
			(stroke
				(width 0.1)
				(type default)
			)
			(layer "F.Fab")
		)
		(fp_line
			(start -0.12065 -0.305054)
			(end -0.12065 -0.2794)
			(stroke
				(width 0.1)
				(type default)
			)
			(layer "F.Fab")
		)
		(fp_line
			(start -0.67945 0.3048)
			(end -0.67945 -0.305054)
			(stroke
				(width 0.1)
				(type default)
			)
			(layer "F.Fab")
		)
		(fp_line
			(start -0.67945 -0.305054)
			(end -0.12065 -0.305054)
			(stroke
				(width 0.1)
				(type default)
			)
			(layer "F.Fab")
		)
		(pad "1" smd circle
			(at -0.40005 0 180)
			(size 0 0)
			(layers "F.Cu" "F.Mask" "F.Paste")
			(net "JTAG_DBP_TDO_R")
		)
		(pad "2" smd circle
			(at 0.40005 0 180)
			(size 0 0)
			(layers "F.Cu" "F.Mask" "F.Paste")
			(net "JTAG_DBP_TDO")
		)
	)
)
